# BASEBOARD_FAB2 (Tioga Pass) — schematic netlist excerpt (pin names and nets, part order shuffled) for the footprints in the layout excerpt that follows; sources: Cadence DE-HDL packaged netlist, KiCad conversion of Wiwynn_Tioga_Pass_MB.brd

C5G87  CAP_A  22.0UF 4V 20% X6S  pkg 0603V  page 243 : A = PVDDQ_GHJ ; B = GND
C8T9  CAP_A  47UF 4V 20% X5R  pkg 0603V  page 225 : A = PVDDQ_GHJ ; B = GND
C5M5  CAP_A  47UF 4V 20% X5R  pkg 0603V  page 220 : A = PVDDQ_DEF ; B = GND

(kicad_pcb
	(version 20260206)
	(generator "pcbnew")
	(generator_version "10.0")
	(general
		(thickness 1.6)
		(legacy_teardrops no)
	)
	(paper "A4")
	(title_block
		(title "Wiwynn_Tioga_Pass_MB.brd")
		(comment 1 "Tioga Pass / footprints 4665-4667 of 4770")
	)
	(layers
		(0 "F.Cu" signal "TOP")
		(4 "In1.Cu" signal "L2GND")
		(6 "In2.Cu" signal "L3")
		(8 "In3.Cu" signal "L4GND")
		(10 "In4.Cu" signal "L5")
		(12 "In5.Cu" signal "L6GND")
		(14 "In6.Cu" signal "L7VCC")
		(16 "In7.Cu" signal "L8VCC")
		(18 "In8.Cu" signal "L9GND")
		(20 "In9.Cu" signal "L10")
		(22 "In10.Cu" signal "L11GND")
		(24 "In11.Cu" signal "L12")
		(26 "In12.Cu" signal "L13GND")
		(2 "B.Cu" signal "BOTTOM")
		(9 "F.Adhes" user "F.Adhesive")
		(11 "B.Adhes" user "B.Adhesive")
		(13 "F.Paste" user "Package Geometry/Pastemask Top")
		(15 "B.Paste" user "Package Geometry/Pastemask Bottom")
		(5 "F.SilkS" user "Ref Des/Silkscreen Top")
		(7 "B.SilkS" user "Ref Des/Silkscreen Bottom")
		(1 "F.Mask" user "Board Geometry/Soldermask Top")
		(3 "B.Mask" user "Board Geometry/Soldermask Bottom")
		(17 "Dwgs.User" user "User.Drawings")
		(19 "Cmts.User" user "User.Comments")
		(21 "Eco1.User" user "User.Eco1")
		(23 "Eco2.User" user "User.Eco2")
		(25 "Edge.Cuts" user "Board Geometry/Outline")
		(27 "Margin" user)
		(31 "F.CrtYd" user "Package Geometry/Place Bound Top")
		(29 "B.CrtYd" user "Package Geometry/Place Bound Bottom")
		(35 "F.Fab" user "Ref Des/Assembly Top")
		(33 "B.Fab" user "Ref Des/Assembly Bottom")
	)
	(footprint ""
		(layer "B.Cu")
		(at 80.731868 -3.3528 -90)
		(property "Reference" "C5G87"
			(at -1.14681 0.76708 0)
			(unlocked yes)
			(layer "B.SilkS")
			(effects
				(font
					(size 0.7874 0.5842)
					(thickness 0.1524)
				)
				(justify mirror)
			)
		)
		(property "Value" ""
			(at 0 0 90)
			(layer "B.Fab")
			(effects
				(font
					(size 1.27 1.27)
				)
				(justify mirror)
			)
		)
		(duplicate_pad_numbers_are_jumpers no)
		(fp_rect
			(start 0.4953 1.6002)
			(end -0.4953 -0.2032)
			(stroke
				(width 0)
				(type default)
			)
			(fill no)
			(layer "B.CrtYd")
		)
		(fp_line
			(start -0.4953 1.6002)
			(end 0.4953 1.6002)
			(stroke
				(width 0.1)
				(type default)
			)
			(layer "B.Fab")
		)
		(fp_line
			(start 0.4953 1.6002)
			(end 0.4953 -0.2032)
			(stroke
				(width 0.1)
				(type default)
			)
			(layer "B.Fab")
		)
		(fp_line
			(start -0.4953 -0.2032)
			(end -0.4953 1.6002)
			(stroke
				(width 0.1)
				(type default)
			)
			(layer "B.Fab")
		)
		(fp_line
			(start 0.4953 -0.2032)
			(end -0.4953 -0.2032)
			(stroke
				(width 0.1)
				(type default)
			)
			(layer "B.Fab")
		)
		(pad "1" smd rect
			(at 0 0 90)
			(size 0.762 0.889)
			(layers "B.Cu" "B.Mask" "B.Paste")
			(net "PVDDQ_GHJ")
		)
		(pad "2" smd rect
			(at 0 1.397 90)
			(size 0.762 0.889)
			(layers "B.Cu" "B.Mask" "B.Paste")
			(net "GND")
		)
		(zone
			(layer "B.Cu")
			(hatch none 0.5)
			(connect_pads
				(clearance 0)
			)
			(min_thickness 0.25)
			(keepout
				(tracks not_allowed)
				(vias allowed)
				(pads allowed)
				(copperpour not_allowed)
				(footprints allowed)
			)
			(placement
				(enabled no)
				(sheetname "")
			)
			(fill
				(thermal_gap 0.5)
				(thermal_bridge_width 0.5)
				(island_removal_mode 0)
			)
			(polygon
				(pts
					(xy 79.779368 -2.9718) (xy 80.287368 -2.9718) (xy 80.287368 -3.7338) (xy 79.779368 -3.7338)
				)
			)
		)
	)
	(footprint ""
		(layer "B.Cu")
		(at 252.1585 -135.4074 -90)
		(property "Reference" "C5M5"
			(at -1.848866 0.752348 270)
			(unlocked yes)
			(layer "B.SilkS")
			(effects
				(font
					(size 1.27 0.9652)
					(thickness 0.1524)
				)
				(justify mirror)
			)
		)
		(property "Value" ""
			(at 0 0 90)
			(layer "B.Fab")
			(effects
				(font
					(size 1.27 1.27)
				)
				(justify mirror)
			)
		)
		(duplicate_pad_numbers_are_jumpers no)
		(fp_rect
			(start 0.500126 1.598422)
			(end -0.500126 -0.201422)
			(stroke
				(width 0)
				(type default)
			)
			(fill no)
			(layer "B.CrtYd")
		)
		(fp_line
			(start -0.500126 1.598422)
			(end 0.500126 1.598422)
			(stroke
				(width 0.1)
				(type default)
			)
			(layer "B.Fab")
		)
		(fp_line
			(start 0.500126 1.598422)
			(end 0.500126 -0.201422)
			(stroke
				(width 0.1)
				(type default)
			)
			(layer "B.Fab")
		)
		(fp_line
			(start -0.500126 -0.201422)
			(end -0.500126 1.598422)
			(stroke
				(width 0.1)
				(type default)
			)
			(layer "B.Fab")
		)
		(fp_line
			(start 0.500126 -0.201422)
			(end -0.500126 -0.201422)
			(stroke
				(width 0.1)
				(type default)
			)
			(layer "B.Fab")
		)
		(pad "1" smd rect
			(at 0 0 180)
			(size 0.889 0.9906)
			(layers "B.Cu" "B.Mask" "B.Paste")
			(net "PVDDQ_DEF")
		)
		(pad "2" smd rect
			(at 0 1.397 180)
			(size 0.889 0.9906)
			(layers "B.Cu" "B.Mask" "B.Paste")
			(net "GND")
		)
		(zone
			(layer "B.Cu")
			(hatch none 0.5)
			(connect_pads
				(clearance 0)
			)
			(min_thickness 0.25)
			(keepout
				(tracks not_allowed)
				(vias allowed)
				(pads allowed)
				(copperpour not_allowed)
				(footprints allowed)
			)
			(placement
				(enabled no)
				(sheetname "")
			)
			(fill
				(thermal_gap 0.5)
				(thermal_bridge_width 0.5)
				(island_removal_mode 0)
			)
			(polygon
				(pts
					(xy 251.206 -134.9121) (xy 251.714 -134.9121) (xy 251.714 -135.9027) (xy 251.206 -135.9027)
				)
			)
		)
		(zone
			(layer "B.Cu")
			(hatch none 0.5)
			(connect_pads
				(clearance 0)
			)
			(min_thickness 0.25)
			(keepout
				(tracks allowed)
				(vias not_allowed)
				(pads allowed)
				(copperpour not_allowed)
				(footprints allowed)
			)
			(placement
				(enabled no)
				(sheetname "")
			)
			(fill
				(thermal_gap 0.5)
				(thermal_bridge_width 0.5)
				(island_removal_mode 0)
			)
			(polygon
				(pts
					(xy 251.206 -134.9121) (xy 251.714 -134.9121) (xy 251.714 -135.9027) (xy 251.206 -135.9027)
				)
			)
		)
	)
	(footprint ""
		(layer "B.Cu")
		(at 83.856068 -17.7546 -90)
		(property "Reference" "C8T9"
			(at -1.848866 0.752348 270)
			(unlocked yes)
			(layer "B.SilkS")
			(effects
				(font
					(size 1.27 0.9652)
					(thickness 0.1524)
				)
				(justify mirror)
			)
		)
		(property "Value" ""
			(at 0 0 90)
			(layer "B.Fab")
			(effects
				(font
					(size 1.27 1.27)
				)
				(justify mirror)
			)
		)
		(duplicate_pad_numbers_are_jumpers no)
		(fp_rect
			(start 0.500126 1.598422)
			(end -0.500126 -0.201422)
			(stroke
				(width 0)
				(type default)
			)
			(fill no)
			(layer "B.CrtYd")
		)
		(fp_line
			(start -0.500126 1.598422)
			(end 0.500126 1.598422)
			(stroke
				(width 0.1)
				(type default)
			)
			(layer "B.Fab")
		)
		(fp_line
			(start 0.500126 1.598422)
			(end 0.500126 -0.201422)
			(stroke
				(width 0.1)
				(type default)
			)
			(layer "B.Fab")
		)
		(fp_line
			(start -0.500126 -0.201422)
			(end -0.500126 1.598422)
			(stroke
				(width 0.1)
				(type default)
			)
			(layer "B.Fab")
		)
		(fp_line
			(start 0.500126 -0.201422)
			(end -0.500126 -0.201422)
			(stroke
				(width 0.1)
				(type default)
			)
			(layer "B.Fab")
		)
		(pad "1" smd rect
			(at 0 0 180)
			(size 0.889 0.9906)
			(layers "B.Cu" "B.Mask" "B.Paste")
			(net "PVDDQ_GHJ")
		)
		(pad "2" smd rect
			(at 0 1.397 180)
			(size 0.889 0.9906)
			(layers "B.Cu" "B.Mask" "B.Paste")
			(net "GND")
		)
		(zone
			(layer "B.Cu")
			(hatch none 0.5)
			(connect_pads
				(clearance 0)
			)
			(min_thickness 0.25)
			(keepout
				(tracks allowed)
				(vias not_allowed)
				(pads allowed)
				(copperpour not_allowed)
				(footprints allowed)
			)
			(placement
				(enabled no)
				(sheetname "")
			)
			(fill
				(thermal_gap 0.5)
				(thermal_bridge_width 0.5)
				(island_removal_mode 0)
			)
			(polygon
				(pts
					(xy 82.903568 -17.2593) (xy 83.411568 -17.2593) (xy 83.411568 -18.2499) (xy 82.903568 -18.2499)
				)
			)
		)
		(zone
			(layer "B.Cu")
			(hatch none 0.5)
			(connect_pads
				(clearance 0)
			)
			(min_thickness 0.25)
			(keepout
				(tracks not_allowed)
				(vias allowed)
				(pads allowed)
				(copperpour not_allowed)
				(footprints allowed)
			)
			(placement
				(enabled no)
				(sheetname "")
			)
			(fill
				(thermal_gap 0.5)
				(thermal_bridge_width 0.5)
				(island_removal_mode 0)
			)
			(polygon
				(pts
					(xy 82.903568 -17.2593) (xy 83.411568 -17.2593) (xy 83.411568 -18.2499) (xy 82.903568 -18.2499)
				)
			)
		)
	)
)
